# S9S_MB_2U (Grand Teton) — schematic netlist excerpt (pin names and nets, part order shuffled) for the footprints in the layout excerpt that follows; sources: Cadence DE-HDL packaged netlist, KiCad conversion of 03242023_DA0F0TMBIJ0_F0T_Motherboard_J_brd_V01_OCP.brd

PR409  Q_RES  0 5% EMPTY  pkg 0402LF  page 278 : A = PVCCD_HV_CPU0_ISYS_R ; B = PVCCD_HV_CPU0_NVDIMM_ISENSE
C376  Q_CAP  47UF 4V 20% X6S  pkg C0805  page 75 : A = PVCCIN_CPU0 ; B = GND
C2074  Q_CAP_DIFFBUS  DIFF BUS_0.22UF 6.3V 20% X6S  pkg C0201  page 181 : \1\ = P3E_PCH_NVS_TX_DN<1> ; \2\ = P3E_PCH_NVS_TX_C_DN<1>

(kicad_pcb
	(version 20260206)
	(generator "pcbnew")
	(generator_version "10.0")
	(general
		(thickness 1.6)
		(legacy_teardrops no)
	)
	(paper "A4")
	(title_block
		(title "03242023_DA0F0TMBIJ0_F0T_Motherboard_J_brd_V01_OCP.brd")
		(comment 1 "Grand Teton / footprints 5164-5166 of 6105")
	)
	(layers
		(0 "F.Cu" signal "TOP")
		(4 "In1.Cu" signal "GND")
		(6 "In2.Cu" signal "IN1")
		(8 "In3.Cu" signal "GND1")
		(10 "In4.Cu" signal "IN2")
		(12 "In5.Cu" signal "GND2")
		(14 "In6.Cu" signal "IN3")
		(16 "In7.Cu" signal "GND3")
		(18 "In8.Cu" signal "VCC")
		(20 "In9.Cu" signal "VCC1")
		(22 "In10.Cu" signal "GND4")
		(24 "In11.Cu" signal "IN4")
		(26 "In12.Cu" signal "GND5")
		(28 "In13.Cu" signal "IN5")
		(30 "In14.Cu" signal "GND6")
		(32 "In15.Cu" signal "IN6")
		(34 "In16.Cu" signal "GND7")
		(2 "B.Cu" signal "BOTTOM")
		(9 "F.Adhes" user "F.Adhesive")
		(11 "B.Adhes" user "B.Adhesive")
		(13 "F.Paste" user "Package Geometry/Pastemask Top")
		(15 "B.Paste" user "Package Geometry/Pastemask Bottom")
		(5 "F.SilkS" user "Ref Des/Silkscreen Top")
		(7 "B.SilkS" user "Ref Des/Silkscreen Bottom")
		(1 "F.Mask" user "Board Geometry/Soldermask Top")
		(3 "B.Mask" user "Board Geometry/Soldermask Bottom")
		(17 "Dwgs.User" user "User.Drawings")
		(19 "Cmts.User" user "User.Comments")
		(21 "Eco1.User" user "User.Eco1")
		(23 "Eco2.User" user "User.Eco2")
		(25 "Edge.Cuts" user "Board Geometry/Outline")
		(27 "Margin" user)
		(31 "F.CrtYd" user "Package Geometry/Place Bound Top")
		(29 "B.CrtYd" user "Package Geometry/Place Bound Bottom")
		(35 "F.Fab" user "Ref Des/Assembly Top")
		(33 "B.Fab" user "Ref Des/Assembly Bottom")
	)
	(footprint ""
		(layer "B.Cu")
		(at 98.511868 -404.486618 -90)
		(property "Reference" "C2074"
			(at 0 0 90)
			(layer "B.SilkS")
			(hide yes)
			(effects
				(font
					(size 1.27 1.27)
				)
				(justify mirror)
			)
		)
		(property "Value" ""
			(at 0 0 90)
			(layer "B.Fab")
			(effects
				(font
					(size 1.27 1.27)
				)
				(justify mirror)
			)
		)
		(duplicate_pad_numbers_are_jumpers no)
		(fp_line
			(start -0.299974 0.150114)
			(end 0.299974 0.150114)
			(stroke
				(width 0.1)
				(type default)
			)
			(layer "B.Fab")
		)
		(fp_line
			(start 0.299974 0.150114)
			(end 0.299974 -0.150114)
			(stroke
				(width 0.1)
				(type default)
			)
			(layer "B.Fab")
		)
		(fp_line
			(start -0.299974 -0.150114)
			(end -0.299974 0.150114)
			(stroke
				(width 0.1)
				(type default)
			)
			(layer "B.Fab")
		)
		(fp_line
			(start 0.299974 -0.150114)
			(end -0.299974 -0.150114)
			(stroke
				(width 0.1)
				(type default)
			)
			(layer "B.Fab")
		)
		(pad "1" smd rect
			(at 0.2667 0 90)
			(size 0.3048 0.381)
			(layers "B.Cu" "B.Mask" "B.Paste")
			(net "P3E_PCH_NVS_TX_DN<1>")
		)
		(pad "2" smd rect
			(at -0.2667 0 90)
			(size 0.3048 0.381)
			(layers "B.Cu" "B.Mask" "B.Paste")
			(net "P3E_PCH_NVS_TX_C_DN<1>")
		)
		(zone
			(layer "In16.Cu")
			(hatch none 0.5)
			(connect_pads
				(clearance 0)
			)
			(min_thickness 0.25)
			(keepout
				(tracks not_allowed)
				(vias allowed)
				(pads allowed)
				(copperpour not_allowed)
				(footprints allowed)
			)
			(placement
				(enabled no)
				(sheetname "")
			)
			(fill
				(thermal_gap 0.5)
				(thermal_bridge_width 0.5)
				(island_removal_mode 0)
			)
			(polygon
				(pts
					(arc
						(start 98.270568 -404.626318)
						(mid 98.292886 -404.572436)
						(end 98.346768 -404.550118)
					)
					(arc
						(start 98.676968 -404.550118)
						(mid 98.73085 -404.572436)
						(end 98.753168 -404.626318)
					)
					(arc
						(start 98.753168 -404.880318)
						(mid 98.73085 -404.9342)
						(end 98.676968 -404.956518)
					)
					(arc
						(start 98.346768 -404.956518)
						(mid 98.292886 -404.9342)
						(end 98.270568 -404.880318)
					)
				)
			)
		)
		(zone
			(layer "In16.Cu")
			(hatch none 0.5)
			(connect_pads
				(clearance 0)
			)
			(min_thickness 0.25)
			(keepout
				(tracks not_allowed)
				(vias allowed)
				(pads allowed)
				(copperpour not_allowed)
				(footprints allowed)
			)
			(placement
				(enabled no)
				(sheetname "")
			)
			(fill
				(thermal_gap 0.5)
				(thermal_bridge_width 0.5)
				(island_removal_mode 0)
			)
			(polygon
				(pts
					(arc
						(start 98.270568 -404.092918)
						(mid 98.292886 -404.039036)
						(end 98.346768 -404.016718)
					)
					(arc
						(start 98.676968 -404.016718)
						(mid 98.73085 -404.039036)
						(end 98.753168 -404.092918)
					)
					(arc
						(start 98.753168 -404.346918)
						(mid 98.73085 -404.4008)
						(end 98.676968 -404.423118)
					)
					(arc
						(start 98.346768 -404.423118)
						(mid 98.292886 -404.4008)
						(end 98.270568 -404.346918)
					)
				)
			)
		)
	)
	(footprint ""
		(layer "B.Cu")
		(at 366.120934 -248.498106 -90)
		(property "Reference" "C376"
			(at 0 0 90)
			(layer "B.SilkS")
			(hide yes)
			(effects
				(font
					(size 1.27 1.27)
				)
				(justify mirror)
			)
		)
		(property "Value" ""
			(at 0 0 90)
			(layer "B.Fab")
			(effects
				(font
					(size 1.27 1.27)
				)
				(justify mirror)
			)
		)
		(duplicate_pad_numbers_are_jumpers no)
		(fp_line
			(start -1.524 0.762)
			(end 1.524 0.762)
			(stroke
				(width 0.1524)
				(type default)
			)
			(layer "B.SilkS")
		)
		(fp_line
			(start 1.524 0.762)
			(end 1.524 -0.762)
			(stroke
				(width 0.1524)
				(type default)
			)
			(layer "B.SilkS")
		)
		(fp_line
			(start -1.524 -0.762)
			(end -1.524 0.762)
			(stroke
				(width 0.1524)
				(type default)
			)
			(layer "B.SilkS")
		)
		(fp_line
			(start 1.524 -0.762)
			(end -1.524 -0.762)
			(stroke
				(width 0.1524)
				(type default)
			)
			(layer "B.SilkS")
		)
		(fp_line
			(start -1.1049 0.724916)
			(end -1.1049 -0.724916)
			(stroke
				(width 0.1)
				(type default)
			)
			(layer "B.Fab")
		)
		(fp_line
			(start 1.1049 0.724916)
			(end -1.1049 0.724916)
			(stroke
				(width 0.1)
				(type default)
			)
			(layer "B.Fab")
		)
		(fp_line
			(start -1.1049 -0.724916)
			(end 1.1049 -0.724916)
			(stroke
				(width 0.1)
				(type default)
			)
			(layer "B.Fab")
		)
		(fp_line
			(start 1.1049 -0.724916)
			(end 1.1049 0.724916)
			(stroke
				(width 0.1)
				(type default)
			)
			(layer "B.Fab")
		)
		(pad "1" smd rect
			(at 0.889 0 270)
			(size 1.016 1.27)
			(layers "B.Cu" "B.Mask" "B.Paste")
			(net "PVCCIN_CPU0")
		)
		(pad "2" smd rect
			(at -0.889 0 270)
			(size 1.016 1.27)
			(layers "B.Cu" "B.Mask" "B.Paste")
			(net "GND")
		)
	)
	(footprint ""
		(layer "B.Cu")
		(at 427.466252 -124.025152)
		(property "Reference" "PR409"
			(at 0 0 0)
			(layer "B.SilkS")
			(hide yes)
			(effects
				(font
					(size 1.27 1.27)
				)
				(justify mirror)
			)
		)
		(property "Value" ""
			(at 0 0 0)
			(layer "B.Fab")
			(effects
				(font
					(size 1.27 1.27)
				)
				(justify mirror)
			)
		)
		(duplicate_pad_numbers_are_jumpers no)
		(fp_line
			(start -0.7874 -0.4064)
			(end -0.7874 0.4064)
			(stroke
				(width 0.1524)
				(type default)
			)
			(layer "B.SilkS")
		)
		(fp_line
			(start -0.7874 0.4064)
			(end 0.7874 0.4064)
			(stroke
				(width 0.1524)
				(type default)
			)
			(layer "B.SilkS")
		)
		(fp_line
			(start 0.7874 -0.4064)
			(end -0.7874 -0.4064)
			(stroke
				(width 0.1524)
				(type default)
			)
			(layer "B.SilkS")
		)
		(fp_line
			(start 0.7874 0.4064)
			(end 0.7874 -0.4064)
			(stroke
				(width 0.1524)
				(type default)
			)
			(layer "B.SilkS")
		)
		(fp_line
			(start -0.67945 -0.3048)
			(end -0.67945 0.3048)
			(stroke
				(width 0.1)
				(type default)
			)
			(layer "B.Fab")
		)
		(fp_line
			(start -0.67945 0.3048)
			(end -0.120396 0.3048)
			(stroke
				(width 0.1)
				(type default)
			)
			(layer "B.Fab")
		)
		(fp_line
			(start -0.12065 -0.3048)
			(end -0.67945 -0.3048)
			(stroke
				(width 0.1)
				(type default)
			)
			(layer "B.Fab")
		)
		(fp_line
			(start -0.12065 -0.2794)
			(end -0.12065 -0.3048)
			(stroke
				(width 0.1)
				(type default)
			)
			(layer "B.Fab")
		)
		(fp_line
			(start -0.120396 0.2794)
			(end 0.12065 0.2794)
			(stroke
				(width 0.1)
				(type default)
			)
			(layer "B.Fab")
		)
		(fp_line
			(start -0.120396 0.3048)
			(end -0.120396 0.2794)
			(stroke
				(width 0.1)
				(type default)
			)
			(layer "B.Fab")
		)
		(fp_line
			(start 0.12065 -0.305054)
			(end 0.12065 -0.2794)
			(stroke
				(width 0.1)
				(type default)
			)
			(layer "B.Fab")
		)
		(fp_line
			(start 0.12065 -0.2794)
			(end -0.12065 -0.2794)
			(stroke
				(width 0.1)
				(type default)
			)
			(layer "B.Fab")
		)
		(fp_line
			(start 0.12065 0.2794)
			(end 0.12065 0.3048)
			(stroke
				(width 0.1)
				(type default)
			)
			(layer "B.Fab")
		)
		(fp_line
			(start 0.12065 0.3048)
			(end 0.67945 0.3048)
			(stroke
				(width 0.1)
				(type default)
			)
			(layer "B.Fab")
		)
		(fp_line
			(start 0.67945 -0.305054)
			(end 0.12065 -0.305054)
			(stroke
				(width 0.1)
				(type default)
			)
			(layer "B.Fab")
		)
		(fp_line
			(start 0.67945 0.3048)
			(end 0.67945 -0.305054)
			(stroke
				(width 0.1)
				(type default)
			)
			(layer "B.Fab")
		)
		(pad "1" smd circle
			(at 0.40005 0 180)
			(size 0 0)
			(layers "B.Cu" "B.Mask" "B.Paste")
			(net "PVCCD_HV_CPU0_ISYS_R")
		)
		(pad "2" smd circle
			(at -0.40005 0 180)
			(size 0 0)
			(layers "B.Cu" "B.Mask" "B.Paste")
			(net "PVCCD_HV_CPU0_NVDIMM_ISENSE")
		)
	)
)
